# S9S_MB_2U (Grand Teton) — schematic netlist excerpt (pin names and nets, part order shuffled) for the footprints in the layout excerpt that follows; sources: Cadence DE-HDL packaged netlist, KiCad conversion of 03242023_DA0F0TMBIJ0_F0T_Motherboard_J_brd_V01_OCP.brd

R2595  Q_RES  0 5% CHIP  pkg 0402LF  page 274 : A = PWRGD_PVCCINFAON_CPU0 ; B = PWRGD_PVCCINFAON_CPU0_R
R2971  Q_RES  0 5% CHIP  pkg 0402LF  page 183 : A = FM_BIOS_DEBUG_EN_N ; B = FM_BIOS_DEBUG_EN_R_N

(kicad_pcb
	(version 20260206)
	(generator "pcbnew")
	(generator_version "10.0")
	(general
		(thickness 1.6)
		(legacy_teardrops no)
	)
	(paper "A4")
	(title_block
		(title "03242023_DA0F0TMBIJ0_F0T_Motherboard_J_brd_V01_OCP.brd")
		(comment 1 "Grand Teton / footprints 4806-4807 of 6105")
	)
	(layers
		(0 "F.Cu" signal "TOP")
		(4 "In1.Cu" signal "GND")
		(6 "In2.Cu" signal "IN1")
		(8 "In3.Cu" signal "GND1")
		(10 "In4.Cu" signal "IN2")
		(12 "In5.Cu" signal "GND2")
		(14 "In6.Cu" signal "IN3")
		(16 "In7.Cu" signal "GND3")
		(18 "In8.Cu" signal "VCC")
		(20 "In9.Cu" signal "VCC1")
		(22 "In10.Cu" signal "GND4")
		(24 "In11.Cu" signal "IN4")
		(26 "In12.Cu" signal "GND5")
		(28 "In13.Cu" signal "IN5")
		(30 "In14.Cu" signal "GND6")
		(32 "In15.Cu" signal "IN6")
		(34 "In16.Cu" signal "GND7")
		(2 "B.Cu" signal "BOTTOM")
		(9 "F.Adhes" user "F.Adhesive")
		(11 "B.Adhes" user "B.Adhesive")
		(13 "F.Paste" user "Package Geometry/Pastemask Top")
		(15 "B.Paste" user "Package Geometry/Pastemask Bottom")
		(5 "F.SilkS" user "Ref Des/Silkscreen Top")
		(7 "B.SilkS" user "Ref Des/Silkscreen Bottom")
		(1 "F.Mask" user "Board Geometry/Soldermask Top")
		(3 "B.Mask" user "Board Geometry/Soldermask Bottom")
		(17 "Dwgs.User" user "User.Drawings")
		(19 "Cmts.User" user "User.Comments")
		(21 "Eco1.User" user "User.Eco1")
		(23 "Eco2.User" user "User.Eco2")
		(25 "Edge.Cuts" user "Board Geometry/Outline")
		(27 "Margin" user)
		(31 "F.CrtYd" user "Package Geometry/Place Bound Top")
		(29 "B.CrtYd" user "Package Geometry/Place Bound Bottom")
		(35 "F.Fab" user "Ref Des/Assembly Top")
		(33 "B.Fab" user "Ref Des/Assembly Bottom")
	)
	(footprint ""
		(layer "B.Cu")
		(at 430.600104 -133.478778)
		(property "Reference" "R2595"
			(at 0 0 0)
			(layer "B.SilkS")
			(hide yes)
			(effects
				(font
					(size 1.27 1.27)
				)
				(justify mirror)
			)
		)
		(property "Value" ""
			(at 0 0 0)
			(layer "B.Fab")
			(effects
				(font
					(size 1.27 1.27)
				)
				(justify mirror)
			)
		)
		(duplicate_pad_numbers_are_jumpers no)
		(fp_line
			(start -0.7874 -0.4064)
			(end -0.7874 0.4064)
			(stroke
				(width 0.1524)
				(type default)
			)
			(layer "B.SilkS")
		)
		(fp_line
			(start -0.7874 0.4064)
			(end 0.7874 0.4064)
			(stroke
				(width 0.1524)
				(type default)
			)
			(layer "B.SilkS")
		)
		(fp_line
			(start 0.7874 -0.4064)
			(end -0.7874 -0.4064)
			(stroke
				(width 0.1524)
				(type default)
			)
			(layer "B.SilkS")
		)
		(fp_line
			(start 0.7874 0.4064)
			(end 0.7874 -0.4064)
			(stroke
				(width 0.1524)
				(type default)
			)
			(layer "B.SilkS")
		)
		(fp_line
			(start -0.67945 -0.3048)
			(end -0.67945 0.3048)
			(stroke
				(width 0.1)
				(type default)
			)
			(layer "B.Fab")
		)
		(fp_line
			(start -0.67945 0.3048)
			(end -0.120396 0.3048)
			(stroke
				(width 0.1)
				(type default)
			)
			(layer "B.Fab")
		)
		(fp_line
			(start -0.12065 -0.3048)
			(end -0.67945 -0.3048)
			(stroke
				(width 0.1)
				(type default)
			)
			(layer "B.Fab")
		)
		(fp_line
			(start -0.12065 -0.2794)
			(end -0.12065 -0.3048)
			(stroke
				(width 0.1)
				(type default)
			)
			(layer "B.Fab")
		)
		(fp_line
			(start -0.120396 0.2794)
			(end 0.12065 0.2794)
			(stroke
				(width 0.1)
				(type default)
			)
			(layer "B.Fab")
		)
		(fp_line
			(start -0.120396 0.3048)
			(end -0.120396 0.2794)
			(stroke
				(width 0.1)
				(type default)
			)
			(layer "B.Fab")
		)
		(fp_line
			(start 0.12065 -0.305054)
			(end 0.12065 -0.2794)
			(stroke
				(width 0.1)
				(type default)
			)
			(layer "B.Fab")
		)
		(fp_line
			(start 0.12065 -0.2794)
			(end -0.12065 -0.2794)
			(stroke
				(width 0.1)
				(type default)
			)
			(layer "B.Fab")
		)
		(fp_line
			(start 0.12065 0.2794)
			(end 0.12065 0.3048)
			(stroke
				(width 0.1)
				(type default)
			)
			(layer "B.Fab")
		)
		(fp_line
			(start 0.12065 0.3048)
			(end 0.67945 0.3048)
			(stroke
				(width 0.1)
				(type default)
			)
			(layer "B.Fab")
		)
		(fp_line
			(start 0.67945 -0.305054)
			(end 0.12065 -0.305054)
			(stroke
				(width 0.1)
				(type default)
			)
			(layer "B.Fab")
		)
		(fp_line
			(start 0.67945 0.3048)
			(end 0.67945 -0.305054)
			(stroke
				(width 0.1)
				(type default)
			)
			(layer "B.Fab")
		)
		(pad "1" smd circle
			(at 0.40005 0 180)
			(size 0 0)
			(layers "B.Cu" "B.Mask" "B.Paste")
			(net "PWRGD_PVCCINFAON_CPU0")
		)
		(pad "2" smd circle
			(at -0.40005 0 180)
			(size 0 0)
			(layers "B.Cu" "B.Mask" "B.Paste")
			(net "PWRGD_PVCCINFAON_CPU0_R")
		)
	)
	(footprint ""
		(layer "B.Cu")
		(at 322.926456 -49.941988 180)
		(property "Reference" "R2971"
			(at 0 0 0)
			(layer "B.SilkS")
			(hide yes)
			(effects
				(font
					(size 1.27 1.27)
				)
				(justify mirror)
			)
		)
		(property "Value" ""
			(at 0 0 0)
			(layer "B.Fab")
			(effects
				(font
					(size 1.27 1.27)
				)
				(justify mirror)
			)
		)
		(duplicate_pad_numbers_are_jumpers no)
		(fp_line
			(start 0.7874 0.4064)
			(end 0.7874 -0.4064)
			(stroke
				(width 0.1524)
				(type default)
			)
			(layer "B.SilkS")
		)
		(fp_line
			(start 0.7874 -0.4064)
			(end -0.7874 -0.4064)
			(stroke
				(width 0.1524)
				(type default)
			)
			(layer "B.SilkS")
		)
		(fp_line
			(start -0.7874 0.4064)
			(end 0.7874 0.4064)
			(stroke
				(width 0.1524)
				(type default)
			)
			(layer "B.SilkS")
		)
		(fp_line
			(start -0.7874 -0.4064)
			(end -0.7874 0.4064)
			(stroke
				(width 0.1524)
				(type default)
			)
			(layer "B.SilkS")
		)
		(fp_line
			(start 0.67945 0.3048)
			(end 0.67945 -0.305054)
			(stroke
				(width 0.1)
				(type default)
			)
			(layer "B.Fab")
		)
		(fp_line
			(start 0.67945 -0.305054)
			(end 0.12065 -0.305054)
			(stroke
				(width 0.1)
				(type default)
			)
			(layer "B.Fab")
		)
		(fp_line
			(start 0.12065 0.3048)
			(end 0.67945 0.3048)
			(stroke
				(width 0.1)
				(type default)
			)
			(layer "B.Fab")
		)
		(fp_line
			(start 0.12065 0.2794)
			(end 0.12065 0.3048)
			(stroke
				(width 0.1)
				(type default)
			)
			(layer "B.Fab")
		)
		(fp_line
			(start 0.12065 -0.2794)
			(end -0.12065 -0.2794)
			(stroke
				(width 0.1)
				(type default)
			)
			(layer "B.Fab")
		)
		(fp_line
			(start 0.12065 -0.305054)
			(end 0.12065 -0.2794)
			(stroke
				(width 0.1)
				(type default)
			)
			(layer "B.Fab")
		)
		(fp_line
			(start -0.120396 0.3048)
			(end -0.120396 0.2794)
			(stroke
				(width 0.1)
				(type default)
			)
			(layer "B.Fab")
		)
		(fp_line
			(start -0.120396 0.2794)
			(end 0.12065 0.2794)
			(stroke
				(width 0.1)
				(type default)
			)
			(layer "B.Fab")
		)
		(fp_line
			(start -0.12065 -0.2794)
			(end -0.12065 -0.3048)
			(stroke
				(width 0.1)
				(type default)
			)
			(layer "B.Fab")
		)
		(fp_line
			(start -0.12065 -0.3048)
			(end -0.67945 -0.3048)
			(stroke
				(width 0.1)
				(type default)
			)
			(layer "B.Fab")
		)
		(fp_line
			(start -0.67945 0.3048)
			(end -0.120396 0.3048)
			(stroke
				(width 0.1)
				(type default)
			)
			(layer "B.Fab")
		)
		(fp_line
			(start -0.67945 -0.3048)
			(end -0.67945 0.3048)
			(stroke
				(width 0.1)
				(type default)
			)
			(layer "B.Fab")
		)
		(pad "1" smd circle
			(at 0.40005 0)
			(size 0 0)
			(layers "B.Cu" "B.Mask" "B.Paste")
			(net "FM_BIOS_DEBUG_EN_N")
		)
		(pad "2" smd circle
			(at -0.40005 0)
			(size 0 0)
			(layers "B.Cu" "B.Mask" "B.Paste")
			(net "FM_BIOS_DEBUG_EN_R_N")
		)
	)
)
